# TIMECARD (Time Appliance Project (Time Card)) — schematic netlist excerpt (pin names and nets, part order shuffled) for the footprints in the layout excerpt that follows; sources: Cadence DE-HDL packaged netlist, KiCad conversion of R4006-B0001-02_R01.brd

C118  CAPACITOR  0.1UF 10V 10%  pkg SMC_0402R_H022  page 14 : \1\ = XP1R0V_FPGA_MGTAVCC ; \2\ = SG
C28  CAPACITOR  0.1UF 10%  pkg SMC_0402R_H022  page 9 : \1\ = C_CPU_RX_PCIE_MGT2_TXP ; \2\ = CPU_RX_PCIE_MGT2_TXP

(kicad_pcb
	(version 20260206)
	(generator "pcbnew")
	(generator_version "10.0")
	(general
		(thickness 1.6)
		(legacy_teardrops no)
	)
	(paper "A4")
	(title_block
		(title "timecard-production-celestica-r4006 — R4006-B0001-02_R01.brd")
		(comment 1 "Time Appliance Project (Time Card) / footprints 857-858 of 1113")
	)
	(layers
		(0 "F.Cu" signal "TOP")
		(4 "In1.Cu" signal "L02_GND1")
		(6 "In2.Cu" signal "L03_SIG1")
		(8 "In3.Cu" signal "L04_GND2")
		(10 "In4.Cu" signal "L05_VCC1")
		(12 "In5.Cu" signal "L06_VCC2")
		(14 "In6.Cu" signal "L07_GND3")
		(16 "In7.Cu" signal "L08_SIG2")
		(18 "In8.Cu" signal "L09_GND4")
		(2 "B.Cu" signal "BOTTOM")
		(9 "F.Adhes" user "F.Adhesive")
		(11 "B.Adhes" user "B.Adhesive")
		(13 "F.Paste" user "Package Geometry/Pastemask Top")
		(15 "B.Paste" user "Package Geometry/Pastemask Bottom")
		(5 "F.SilkS" user "Ref Des/Silkscreen Top")
		(7 "B.SilkS" user "Ref Des/Silkscreen Bottom")
		(1 "F.Mask" user "Board Geometry/Soldermask Top")
		(3 "B.Mask" user "Board Geometry/Soldermask Bottom")
		(17 "Dwgs.User" user "User.Drawings")
		(19 "Cmts.User" user "User.Comments")
		(21 "Eco1.User" user "User.Eco1")
		(23 "Eco2.User" user "User.Eco2")
		(25 "Edge.Cuts" user "Board Geometry/Outline")
		(27 "Margin" user)
		(31 "F.CrtYd" user "Package Geometry/Place Bound Top")
		(29 "B.CrtYd" user "Package Geometry/Place Bound Bottom")
		(35 "F.Fab" user "Ref Des/Assembly Top")
		(33 "B.Fab" user "Ref Des/Assembly Bottom")
	)
	(footprint ""
		(layer "B.Cu")
		(at 104.347264 -39.823136 180)
		(property "Reference" "C118"
			(at 41.400984 -1.251966 0)
			(unlocked yes)
			(layer "B.SilkS")
			(effects
				(font
					(size 0.635 0.4064)
					(thickness 0.1524)
				)
				(justify mirror)
			)
		)
		(property "Value" "VAL*"
			(at 0 3.718306 180)
			(unlocked yes)
			(layer "B.Fab")
			(hide yes)
			(effects
				(font
					(size 0.7874 0.5842)
					(thickness 0.127)
				)
				(justify mirror)
			)
		)
		(property "Tolerance" "TOL*"
			(at 0 4.861306 180)
			(unlocked yes)
			(layer "Cmts.User")
			(hide yes)
			(effects
				(font
					(size 0.7874 0.5842)
					(thickness 0.127)
				)
				(justify mirror)
			)
		)
		(property "User Part Number" "PARTNUM*"
			(at 0 2.575306 180)
			(unlocked yes)
			(layer "Cmts.User")
			(hide yes)
			(effects
				(font
					(size 0.7874 0.5842)
					(thickness 0.127)
				)
				(justify mirror)
			)
		)
		(property "Device Type" "CAPACITOR-G105-0B104-CK,0.1UF,A"
			(at 0 1.432306 180)
			(unlocked yes)
			(layer "B.Fab")
			(hide yes)
			(effects
				(font
					(size 0.7874 0.5842)
					(thickness 0.127)
				)
				(justify mirror)
			)
		)
		(duplicate_pad_numbers_are_jumpers no)
		(fp_line
			(start 0.970026 0.4699)
			(end 0.970026 -0.4699)
			(stroke
				(width 0.1)
				(type default)
			)
			(layer "B.SilkS")
		)
		(fp_line
			(start 0.970026 -0.4699)
			(end -0.970026 -0.4699)
			(stroke
				(width 0.1)
				(type default)
			)
			(layer "B.SilkS")
		)
		(fp_line
			(start -0.970026 0.4699)
			(end 0.970026 0.4699)
			(stroke
				(width 0.1)
				(type default)
			)
			(layer "B.SilkS")
		)
		(fp_line
			(start -0.970026 -0.4699)
			(end -0.970026 0.4699)
			(stroke
				(width 0.1)
				(type default)
			)
			(layer "B.SilkS")
		)
		(fp_poly
			(pts
				(xy 0.970026 0.4699) (xy -0.970026 0.4699) (xy -0.970026 -0.4699) (xy 0.970026 -0.4699)
			)
			(stroke
				(width 0)
				(type default)
			)
			(fill no)
			(layer "B.CrtYd")
		)
		(fp_line
			(start 0.508 0.3048)
			(end 0.508 -0.3048)
			(stroke
				(width 0.1)
				(type default)
			)
			(layer "B.Fab")
		)
		(fp_line
			(start 0.508 -0.3048)
			(end -0.508 -0.3048)
			(stroke
				(width 0.1)
				(type default)
			)
			(layer "B.Fab")
		)
		(fp_line
			(start -0.508 0.3048)
			(end 0.508 0.3048)
			(stroke
				(width 0.1)
				(type default)
			)
			(layer "B.Fab")
		)
		(fp_line
			(start -0.508 -0.3048)
			(end -0.508 0.3048)
			(stroke
				(width 0.1)
				(type default)
			)
			(layer "B.Fab")
		)
		(pad "1" smd circle
			(at 0.500126 0)
			(size 0.635 0.635)
			(layers "B.Cu" "B.Mask" "B.Paste")
			(net "XP1R0V_FPGA_MGTAVCC")
		)
		(pad "2" smd circle
			(at -0.500126 0)
			(size 0.635 0.635)
			(layers "B.Cu" "B.Mask" "B.Paste")
			(net "SG")
		)
	)
	(footprint ""
		(layer "B.Cu")
		(at 71.13397 -15.367 -90)
		(property "Reference" "C28"
			(at 2.286 0.17272 270)
			(unlocked yes)
			(layer "B.SilkS")
			(effects
				(font
					(size 0.635 0.4064)
					(thickness 0.1524)
				)
				(justify mirror)
			)
		)
		(property "Value" "VAL*"
			(at -0.0762 2.067306 270)
			(unlocked yes)
			(layer "B.Fab")
			(hide yes)
			(effects
				(font
					(size 0.7874 0.5842)
					(thickness 0.1524)
				)
				(justify mirror)
			)
		)
		(property "Tolerance" "TOL*"
			(at -0.0762 3.032506 270)
			(unlocked yes)
			(layer "Cmts.User")
			(hide yes)
			(effects
				(font
					(size 0.7874 0.5842)
					(thickness 0.1524)
				)
				(justify mirror)
			)
		)
		(property "User Part Number" "PARTNUM*"
			(at -0.1016 4.023106 270)
			(unlocked yes)
			(layer "Cmts.User")
			(hide yes)
			(effects
				(font
					(size 0.7874 0.5842)
					(thickness 0.1524)
				)
				(justify mirror)
			)
		)
		(property "Device Type" "CAPACITOR-G105-0B104-CK,0.1UF,A"
			(at -0.0508 1.127506 270)
			(unlocked yes)
			(layer "B.Fab")
			(hide yes)
			(effects
				(font
					(size 0.7874 0.5842)
					(thickness 0.1524)
				)
				(justify mirror)
			)
		)
		(duplicate_pad_numbers_are_jumpers no)
		(fp_line
			(start -1.143 0.5588)
			(end -1.143 -0.5588)
			(stroke
				(width 0.1)
				(type default)
			)
			(layer "B.SilkS")
		)
		(fp_line
			(start 1.143 0.5588)
			(end -1.143 0.5588)
			(stroke
				(width 0.1)
				(type default)
			)
			(layer "B.SilkS")
		)
		(fp_line
			(start -1.143 -0.5588)
			(end 1.143 -0.5588)
			(stroke
				(width 0.1)
				(type default)
			)
			(layer "B.SilkS")
		)
		(fp_line
			(start 1.143 -0.5588)
			(end 1.143 0.5588)
			(stroke
				(width 0.1)
				(type default)
			)
			(layer "B.SilkS")
		)
		(fp_rect
			(start 1.143 0.5588)
			(end -1.143 -0.5588)
			(stroke
				(width 0)
				(type default)
			)
			(fill no)
			(layer "B.CrtYd")
		)
		(fp_line
			(start -0.508 0.3048)
			(end -0.508 -0.3048)
			(stroke
				(width 0.1)
				(type default)
			)
			(layer "B.Fab")
		)
		(fp_line
			(start 0.508 0.3048)
			(end -0.508 0.3048)
			(stroke
				(width 0.1)
				(type default)
			)
			(layer "B.Fab")
		)
		(fp_line
			(start -0.508 -0.3048)
			(end 0.508 -0.3048)
			(stroke
				(width 0.1)
				(type default)
			)
			(layer "B.Fab")
		)
		(fp_line
			(start 0.508 -0.3048)
			(end 0.508 0.3048)
			(stroke
				(width 0.1)
				(type default)
			)
			(layer "B.Fab")
		)
		(pad "1" smd rect
			(at 0.5334 0 90)
			(size 0.7112 0.6096)
			(layers "B.Cu" "B.Mask" "B.Paste")
			(net "C_CPU_RX_PCIE_MGT2_TXP")
		)
		(pad "2" smd rect
			(at -0.5334 0 90)
			(size 0.7112 0.6096)
			(layers "B.Cu" "B.Mask" "B.Paste")
			(net "CPU_RX_PCIE_MGT2_TXP")
		)
		(zone
			(layer "B.Cu")
			(hatch none 0.5)
			(connect_pads
				(clearance 0)
			)
			(min_thickness 0.25)
			(keepout
				(tracks allowed)
				(vias not_allowed)
				(pads allowed)
				(copperpour not_allowed)
				(footprints allowed)
			)
			(placement
				(enabled no)
				(sheetname "")
			)
			(fill
				(thermal_gap 0.5)
				(thermal_bridge_width 0.5)
				(island_removal_mode 0)
			)
			(polygon
				(pts
					(xy 70.82917 -15.2908) (xy 71.43877 -15.2908) (xy 71.43877 -15.4432) (xy 70.82917 -15.4432)
				)
			)
		)
	)
)
